G04*
G04 #@! TF.GenerationSoftware,Altium Limited,Altium Designer,22.4.2 (48)*
G04*
G04 Layer_Color=128*
%FSLAX25Y25*%
%MOIN*%
G70*
G04*
G04 #@! TF.SameCoordinates,446674BB-F454-490D-8607-5140536C8ADF*
G04*
G04*
G04 #@! TF.FilePolarity,Positive*
G04*
G01*
G75*
%ADD182C,0.00200*%
D182*
X140591Y-120079D02*
X144134D01*
X142362Y-121850D02*
Y-118307D01*
X150591Y-120079D02*
X154134D01*
X152362Y-121850D02*
Y-118307D01*
X160591Y-120079D02*
X164134D01*
X162362Y-121850D02*
Y-118307D01*
X170591Y-120079D02*
X174134D01*
X172362Y-121850D02*
Y-118307D01*
X255972Y-327165D02*
X260972D01*
X258472Y-329665D02*
Y-324665D01*
X279784Y-327165D02*
X284784D01*
X282283Y-329665D02*
Y-324665D01*
X291595Y-327165D02*
X296595D01*
X294094Y-329665D02*
Y-324665D01*
X299862Y-156693D02*
X304862D01*
X302362Y-159193D02*
Y-154193D01*
X299862Y-316535D02*
X304862D01*
X302362Y-319035D02*
Y-314035D01*
X140020Y-316535D02*
X145020D01*
X142520Y-319035D02*
Y-314035D01*
X140020Y-236614D02*
X145020D01*
X142520Y-239114D02*
Y-234114D01*
X140020Y-156693D02*
X145020D01*
X142520Y-159193D02*
Y-154193D01*
X267972Y-327165D02*
X272972D01*
X270472Y-329665D02*
Y-324665D01*
X243972Y-327165D02*
X248972D01*
X246472Y-329665D02*
Y-324665D01*
X668504Y-194488D02*
X680315D01*
X674409Y-200394D02*
Y-188583D01*
X642126Y-194488D02*
X649213D01*
X645669Y-198031D02*
Y-190945D01*
X620472Y-194488D02*
X627559D01*
X624016Y-198031D02*
Y-190945D01*
X620472Y-177953D02*
X627559D01*
X624016Y-181496D02*
Y-174409D01*
X642126Y-177953D02*
X649213D01*
X645669Y-181496D02*
Y-174409D01*
X620472Y-161417D02*
X627559D01*
X624016Y-164961D02*
Y-157874D01*
X642126Y-161417D02*
X649213D01*
X645669Y-164961D02*
Y-157874D01*
X668504Y-161417D02*
X680315D01*
X674409Y-167323D02*
Y-155512D01*
X390461Y-160477D02*
X392628D01*
X391545Y-161560D02*
Y-159394D01*
X469202Y-160477D02*
X471368D01*
X470285Y-161560D02*
Y-159394D01*
X527312Y-194680D02*
X529478D01*
X528395Y-195763D02*
Y-193597D01*
X527312Y-273420D02*
X529478D01*
X528395Y-274503D02*
Y-272337D01*
X469192Y-308597D02*
X471358D01*
X470275Y-309681D02*
Y-307515D01*
X390452Y-308597D02*
X392618D01*
X391535Y-309681D02*
Y-307515D01*
X339821Y-273410D02*
X341987D01*
X340904Y-274493D02*
Y-272327D01*
X339821Y-194670D02*
X341987D01*
X340904Y-195753D02*
Y-193587D01*
X527110Y-312764D02*
X538921D01*
X533015Y-318670D02*
Y-306858D01*
X330510Y-155764D02*
X342321D01*
X336415Y-161670D02*
Y-149858D01*
X330610Y-312764D02*
X342421D01*
X336515Y-318670D02*
Y-306858D01*
X527110Y-155764D02*
X538921D01*
X533015Y-161670D02*
Y-149858D01*
X600992Y-330039D02*
X607590D01*
X604291Y-333339D02*
Y-326740D01*
X570992Y-330039D02*
X577591D01*
X574291Y-333339D02*
Y-326740D01*
X-21811Y-326781D02*
X-15118D01*
X-18464Y-330128D02*
Y-323435D01*
X-11417Y-316781D02*
X-5512D01*
X-8465Y-319734D02*
Y-313828D01*
X-1811Y-326781D02*
X4882D01*
X1535Y-330128D02*
Y-323435D01*
X-1811Y-306781D02*
X4882D01*
X1535Y-310128D02*
Y-303435D01*
X-21811Y-306781D02*
X-15118D01*
X-18464Y-310128D02*
Y-303435D01*
X-21811Y-273630D02*
X-15118D01*
X-18465Y-276976D02*
Y-270284D01*
X-11417Y-263630D02*
X-5512D01*
X-8465Y-266583D02*
Y-260677D01*
X-1811Y-273630D02*
X4882D01*
X1535Y-276976D02*
Y-270284D01*
X-1811Y-253630D02*
X4882D01*
X1535Y-256976D02*
Y-250284D01*
X-21811Y-253630D02*
X-15118D01*
X-18465Y-256976D02*
Y-250284D01*
X-21811Y-220480D02*
X-15118D01*
X-18465Y-223827D02*
Y-217134D01*
X-11417Y-210480D02*
X-5512D01*
X-8465Y-213433D02*
Y-207528D01*
X-1811Y-220480D02*
X4882D01*
X1535Y-223827D02*
Y-217134D01*
X-1811Y-200480D02*
X4882D01*
X1535Y-203827D02*
Y-197134D01*
X-21811Y-200480D02*
X-15118D01*
X-18465Y-203827D02*
Y-197134D01*
X-21811Y-167332D02*
X-15118D01*
X-18464Y-170679D02*
Y-163986D01*
X-11417Y-157332D02*
X-5512D01*
X-8465Y-160285D02*
Y-154379D01*
X-1811Y-167332D02*
X4882D01*
X1535Y-170679D02*
Y-163986D01*
X-1811Y-147332D02*
X4882D01*
X1535Y-150679D02*
Y-143986D01*
X-21811Y-147332D02*
X-15118D01*
X-18464Y-150679D02*
Y-143986D01*
X639144Y-33710D02*
X642136D01*
X640640Y-35206D02*
Y-32214D01*
X639144Y-17962D02*
X642136D01*
X640640Y-19458D02*
Y-16466D01*
X81289Y-53986D02*
X84281D01*
X82785Y-55482D02*
Y-52490D01*
X81289Y-69734D02*
X84281D01*
X82785Y-71230D02*
Y-68238D01*
X587284Y13937D02*
X590827D01*
X589055Y12165D02*
Y15709D01*
X577283Y13937D02*
X580827D01*
X579055Y12165D02*
Y15709D01*
X567283Y13937D02*
X570827D01*
X569055Y12165D02*
Y15709D01*
X557283Y13937D02*
X560827D01*
X559055Y12165D02*
Y15709D01*
X547284Y13937D02*
X550827D01*
X549055Y12165D02*
Y15709D01*
X537284Y13937D02*
X540827D01*
X539055Y12165D02*
Y15709D01*
X587284Y3937D02*
X590827D01*
X589055Y2165D02*
Y5709D01*
X577283Y3937D02*
X580827D01*
X579055Y2165D02*
Y5709D01*
X567283Y3937D02*
X570827D01*
X569055Y2165D02*
Y5709D01*
X557283Y3937D02*
X560827D01*
X559055Y2165D02*
Y5709D01*
X547284Y3937D02*
X550827D01*
X549055Y2165D02*
Y5709D01*
X537284Y3937D02*
X540827D01*
X539055Y2165D02*
Y5709D01*
X-6260Y0D02*
X6260D01*
X0Y-6260D02*
Y6260D01*
X-6260Y-378395D02*
X6260D01*
X0Y-384655D02*
Y-372135D01*
X416435Y-196581D02*
X417235D01*
X416835Y-196981D02*
Y-196181D01*
X411411Y-196850D02*
X412211D01*
X411811Y-197250D02*
Y-196450D01*
X610617Y-227953D02*
X612217D01*
X611417Y-228753D02*
Y-227153D01*
X610617Y-223228D02*
X612217D01*
X611417Y-224028D02*
Y-222428D01*
X603924Y-227953D02*
X605524D01*
X604724Y-228753D02*
Y-227153D01*
X592907Y-127953D02*
X593707D01*
X593307Y-128353D02*
Y-127553D01*
X570466Y-70472D02*
X571266D01*
X570866Y-70872D02*
Y-70072D01*
X570466Y-72441D02*
X571266D01*
X570866Y-72841D02*
Y-72041D01*
X570466Y-74410D02*
X571266D01*
X570866Y-74809D02*
Y-74010D01*
X573616Y-70472D02*
X574416D01*
X574016Y-70872D02*
Y-70072D01*
X573616Y-72441D02*
X574416D01*
X574016Y-72841D02*
Y-72041D01*
X573616Y-74410D02*
X574416D01*
X574016Y-74809D02*
Y-74010D01*
X350387Y-116929D02*
X351187D01*
X350787Y-117329D02*
Y-116529D01*
X352356Y-116929D02*
X353156D01*
X352756Y-117329D02*
Y-116529D01*
X354324Y-116929D02*
X355124D01*
X354724Y-117329D02*
Y-116529D01*
X350387Y-113779D02*
X351187D01*
X350787Y-114180D02*
Y-113380D01*
X352356Y-113779D02*
X353156D01*
X352756Y-114180D02*
Y-113380D01*
X354324Y-113779D02*
X355124D01*
X354724Y-114180D02*
Y-113380D01*
X378734Y-137795D02*
X379534D01*
X379134Y-138195D02*
Y-137395D01*
X375584Y-120079D02*
X376384D01*
X375984Y-120479D02*
Y-119679D01*
X375132Y-123610D02*
X375932D01*
X375532Y-124010D02*
Y-123210D01*
X314258Y-244775D02*
X315058D01*
X314658Y-245175D02*
Y-244375D01*
X314697Y-235081D02*
X315497D01*
X315097Y-235481D02*
Y-234681D01*
X314826Y-230634D02*
X315626D01*
X315226Y-231034D02*
Y-230234D01*
X314464Y-227997D02*
X315265D01*
X314864Y-228397D02*
Y-227597D01*
X314103Y-225180D02*
X314903D01*
X314503Y-225580D02*
Y-224780D01*
X288183Y-225590D02*
X288983D01*
X288583Y-225991D02*
Y-225190D01*
X287789Y-228740D02*
X288589D01*
X288189Y-229140D02*
Y-228340D01*
X287789Y-231102D02*
X288589D01*
X288189Y-231502D02*
Y-230702D01*
X287657Y-233478D02*
X288457D01*
X288057Y-233878D02*
Y-233078D01*
X287657Y-245095D02*
X288457D01*
X288057Y-245495D02*
Y-244695D01*
X287789Y-247638D02*
X288589D01*
X288189Y-248038D02*
Y-247238D01*
X287541Y-241819D02*
X288341D01*
X287941Y-242219D02*
Y-241419D01*
X287789Y-235827D02*
X288589D01*
X288189Y-236227D02*
Y-235427D01*
X588576Y-302756D02*
X589376D01*
X588976Y-303156D02*
Y-302356D01*
X579128Y-303150D02*
X579928D01*
X579528Y-303550D02*
Y-302750D01*
X615348Y-305512D02*
X616148D01*
X615748Y-305912D02*
Y-305112D01*
X562198Y-306693D02*
X562998D01*
X562598Y-307093D02*
Y-306293D01*
X330309Y-120473D02*
X331109D01*
X330709Y-120872D02*
Y-120072D01*
X330309Y-123425D02*
X331109D01*
X330709Y-123825D02*
Y-123025D01*
X120663Y-263632D02*
X121463D01*
X121063Y-264032D02*
Y-263231D01*
X346811Y-89891D02*
X349611D01*
X348211Y-91291D02*
Y-88491D01*
X356398Y-89963D02*
X359198D01*
X357798Y-91363D02*
Y-88563D01*
X375190Y-127165D02*
X375991D01*
X375590Y-127565D02*
Y-126765D01*
X105899Y-263632D02*
X106699D01*
X106299Y-264032D02*
Y-263231D01*
X330309Y-126378D02*
X331109D01*
X330709Y-126778D02*
Y-125978D01*
X564601Y-236697D02*
X565191D01*
X564896Y-236992D02*
Y-236402D01*
X599600Y-146063D02*
X600400D01*
X600000Y-146463D02*
Y-145663D01*
X597632Y-146063D02*
X598431D01*
X598032Y-146463D02*
Y-145663D01*
X595663Y-146063D02*
X596463D01*
X596063Y-146463D02*
Y-145663D01*
X586608Y-146063D02*
X587408D01*
X587008Y-146463D02*
Y-145663D01*
X584639Y-146063D02*
X585439D01*
X585039Y-146463D02*
Y-145663D01*
X582671Y-146063D02*
X583471D01*
X583071Y-146463D02*
Y-145663D01*
X575584Y-145669D02*
X576384D01*
X575984Y-146069D02*
Y-145269D01*
X573616Y-145669D02*
X574416D01*
X574016Y-146069D02*
Y-145269D01*
X571647Y-145669D02*
X572447D01*
X572047Y-146069D02*
Y-145269D01*
X592907Y-131102D02*
X593707D01*
X593307Y-131502D02*
Y-130702D01*
X594876Y-131102D02*
X595676D01*
X595276Y-131502D02*
Y-130702D01*
X596844Y-131102D02*
X597644D01*
X597244Y-131502D02*
Y-130702D01*
X594876Y-127953D02*
X595676D01*
X595276Y-128353D02*
Y-127553D01*
X596844Y-127953D02*
X597644D01*
X597244Y-128353D02*
Y-127553D01*
X598019Y-228346D02*
X599619D01*
X598819Y-229147D02*
Y-227547D01*
X603924Y-222835D02*
X605524D01*
X604724Y-223635D02*
Y-222035D01*
X650387Y-229921D02*
X651187D01*
X650787Y-230321D02*
Y-229521D01*
X645269Y-230315D02*
X646069D01*
X645669Y-230715D02*
Y-229915D01*
X641332Y-230315D02*
X642132D01*
X641732Y-230715D02*
Y-229915D01*
X637789Y-230315D02*
X638589D01*
X638189Y-230715D02*
Y-229915D01*
X640545Y-250394D02*
X641345D01*
X640945Y-250794D02*
Y-249994D01*
X640545Y-248425D02*
X641345D01*
X640945Y-248825D02*
Y-248025D01*
X640545Y-246457D02*
X641345D01*
X640945Y-246857D02*
Y-246057D01*
X637395Y-250394D02*
X638195D01*
X637795Y-250794D02*
Y-249994D01*
X637395Y-248425D02*
X638195D01*
X637795Y-248825D02*
Y-248025D01*
X637395Y-246457D02*
X638195D01*
X637795Y-246857D02*
Y-246057D01*
X654324Y-211417D02*
X655124D01*
X654724Y-211817D02*
Y-211017D01*
X656293Y-211417D02*
X657093D01*
X656693Y-211817D02*
Y-211017D01*
X658261Y-211417D02*
X659061D01*
X658661Y-211817D02*
Y-211017D01*
X654324Y-208268D02*
X655124D01*
X654724Y-208668D02*
Y-207868D01*
X656293Y-208268D02*
X657093D01*
X656693Y-208668D02*
Y-207868D01*
X658261Y-208268D02*
X659061D01*
X658661Y-208668D02*
Y-207868D01*
X675190Y-298819D02*
X675990D01*
X675591Y-299219D02*
Y-298419D01*
X673222Y-298819D02*
X674022D01*
X673622Y-299219D02*
Y-298419D01*
X671253Y-298819D02*
X672053D01*
X671654Y-299219D02*
Y-298419D01*
X675190Y-301969D02*
X675990D01*
X675591Y-302368D02*
Y-301569D01*
X673222Y-301969D02*
X674022D01*
X673622Y-302368D02*
Y-301569D01*
X671253Y-301969D02*
X672053D01*
X671654Y-302368D02*
Y-301569D01*
X157080Y-358661D02*
X157880D01*
X157480Y-359061D02*
Y-358261D01*
X155112Y-358661D02*
X155912D01*
X155512Y-359061D02*
Y-358261D01*
X153143Y-358661D02*
X153943D01*
X153543Y-359061D02*
Y-358261D01*
X157080Y-361811D02*
X157880D01*
X157480Y-362211D02*
Y-361411D01*
X155112Y-361811D02*
X155912D01*
X155512Y-362211D02*
Y-361411D01*
X153143Y-361811D02*
X153943D01*
X153543Y-362211D02*
Y-361411D01*
X154324Y-389616D02*
X155124D01*
X154724Y-390016D02*
Y-389216D01*
X156293Y-389616D02*
X157093D01*
X156693Y-390016D02*
Y-389216D01*
X158261Y-389616D02*
X159061D01*
X158661Y-390016D02*
Y-389216D01*
X154324Y-386466D02*
X155124D01*
X154724Y-386866D02*
Y-386066D01*
X156293Y-386466D02*
X157093D01*
X156693Y-386866D02*
Y-386066D01*
X158261Y-386466D02*
X159061D01*
X158661Y-386866D02*
Y-386066D01*
X575519Y-236906D02*
X576319D01*
X575919Y-237305D02*
Y-236506D01*
X596302Y-247441D02*
X597102D01*
X596702Y-247841D02*
Y-247041D01*
X591578Y-247441D02*
X592378D01*
X591978Y-247841D02*
Y-247041D01*
X586066Y-247441D02*
X586866D01*
X586466Y-247841D02*
Y-247041D01*
X580554Y-207189D02*
X581354D01*
X580954Y-207589D02*
Y-206789D01*
X580535Y-237412D02*
X581335D01*
X580935Y-237812D02*
Y-237012D01*
X554119Y-212889D02*
X554919D01*
X554519Y-213289D02*
Y-212489D01*
X546019Y-246106D02*
X546819D01*
X546419Y-246505D02*
Y-245706D01*
X626419Y-244005D02*
X627219D01*
X626819Y-244406D02*
Y-243605D01*
X610694Y-248110D02*
X611494D01*
X611094Y-248510D02*
Y-247710D01*
X602602Y-247441D02*
X603402D01*
X603002Y-247841D02*
Y-247041D01*
X531096Y-262647D02*
X531896D01*
X531496Y-263047D02*
Y-262247D01*
X461411Y-310679D02*
X462211D01*
X461811Y-311079D02*
Y-310279D01*
X449600Y-293750D02*
X450400D01*
X450000Y-294150D02*
Y-293350D01*
X422041Y-293789D02*
X422841D01*
X422441Y-294189D02*
Y-293389D01*
X531096Y-213435D02*
X531896D01*
X531496Y-213835D02*
Y-213035D01*
X338125Y-243567D02*
X338925D01*
X338525Y-243967D02*
Y-243167D01*
X525191Y-233088D02*
X525991D01*
X525591Y-233488D02*
Y-232688D01*
X439297Y-162549D02*
X440097D01*
X439697Y-162949D02*
Y-162149D01*
X342744Y-225173D02*
X343544D01*
X343144Y-225573D02*
Y-224773D01*
X420269Y-157923D02*
X421069D01*
X420669Y-158323D02*
Y-157523D01*
X531096Y-223277D02*
X531896D01*
X531496Y-223677D02*
Y-222877D01*
X338183Y-235236D02*
X338983D01*
X338583Y-235636D02*
Y-234836D01*
X525191Y-242962D02*
X525991D01*
X525591Y-243362D02*
Y-242562D01*
X429750Y-162253D02*
X430550D01*
X430150Y-162654D02*
Y-161854D01*
X343044Y-215373D02*
X343844D01*
X343444Y-215773D02*
Y-214973D01*
X431883Y-293750D02*
X432684D01*
X432283Y-294150D02*
Y-293350D01*
X410128Y-157923D02*
X410928D01*
X410528Y-158323D02*
Y-157523D01*
X342544Y-264473D02*
X343344D01*
X342944Y-264873D02*
Y-264073D01*
X443694Y-293750D02*
X444494D01*
X444095Y-294150D02*
Y-293350D01*
X422435Y-311072D02*
X423235D01*
X422835Y-311472D02*
Y-310672D01*
X531096Y-233088D02*
X531896D01*
X531496Y-233488D02*
Y-232688D01*
X429750Y-157923D02*
X430550D01*
X430150Y-158323D02*
Y-157523D01*
X338044Y-225173D02*
X338844D01*
X338444Y-225573D02*
Y-224773D01*
X402356Y-311072D02*
X403156D01*
X402756Y-311472D02*
Y-310672D01*
X525191Y-253969D02*
X525991D01*
X525591Y-254368D02*
Y-253569D01*
X419679Y-162549D02*
X420479D01*
X420079Y-162949D02*
Y-162149D01*
X343003Y-205651D02*
X343803D01*
X343403Y-206051D02*
Y-205251D01*
X525191Y-203592D02*
X525991D01*
X525591Y-203992D02*
Y-203192D01*
X399895Y-157824D02*
X400695D01*
X400295Y-158224D02*
Y-157424D01*
X342744Y-254773D02*
X343544D01*
X343144Y-255173D02*
Y-254373D01*
X431528Y-311189D02*
X432328D01*
X431928Y-311589D02*
Y-310789D01*
X531096Y-242962D02*
X531896D01*
X531496Y-243362D02*
Y-242562D01*
X338444Y-215273D02*
X339244D01*
X338844Y-215673D02*
Y-214873D01*
X401962Y-293750D02*
X402762D01*
X402362Y-294150D02*
Y-293350D01*
X525191Y-262647D02*
X525991D01*
X525591Y-263047D02*
Y-262247D01*
X410513Y-162758D02*
X411313D01*
X410913Y-163157D02*
Y-162357D01*
X338044Y-264473D02*
X338844D01*
X338444Y-264873D02*
Y-264073D01*
X455899Y-293750D02*
X456699D01*
X456299Y-294150D02*
Y-293350D01*
X437395Y-293750D02*
X438195D01*
X437795Y-294150D02*
Y-293350D01*
X525191Y-213435D02*
X525991D01*
X525591Y-213835D02*
Y-213035D01*
X458919Y-162510D02*
X459719D01*
X459319Y-162910D02*
Y-162110D01*
X458919Y-157922D02*
X459719D01*
X459319Y-158322D02*
Y-157522D01*
X342344Y-243747D02*
X343144D01*
X342744Y-244147D02*
Y-243347D01*
X412198Y-311072D02*
X412998D01*
X412598Y-311472D02*
Y-310672D01*
X531096Y-253969D02*
X531896D01*
X531496Y-254368D02*
Y-253569D01*
X449403Y-157923D02*
X450203D01*
X449803Y-158323D02*
Y-157523D01*
X338344Y-205473D02*
X339144D01*
X338744Y-205873D02*
Y-205073D01*
X531096Y-203592D02*
X531896D01*
X531496Y-203992D02*
Y-203192D01*
X400879Y-162509D02*
X401680D01*
X401279Y-162909D02*
Y-162109D01*
X439561Y-157923D02*
X440361D01*
X439961Y-158323D02*
Y-157523D01*
X338044Y-254773D02*
X338844D01*
X338444Y-255173D02*
Y-254373D01*
X461017Y-293750D02*
X461817D01*
X461417Y-294150D02*
Y-293350D01*
X525191Y-223277D02*
X525991D01*
X525591Y-223677D02*
Y-222877D01*
X449108Y-162549D02*
X449908D01*
X449508Y-162949D02*
Y-162149D01*
X343104Y-235236D02*
X343904D01*
X343504Y-235636D02*
Y-234836D01*
X411805Y-293750D02*
X412605D01*
X412205Y-294150D02*
Y-293350D01*
X639350Y-314581D02*
X640150D01*
X639750Y-314981D02*
Y-314181D01*
X658247Y-314581D02*
X659047D01*
X658647Y-314981D02*
Y-314181D01*
X509005Y-345138D02*
X509805D01*
X509405Y-345538D02*
Y-344738D01*
X508611Y-330177D02*
X509411D01*
X509011Y-330577D02*
Y-329777D01*
X56041Y-143600D02*
X56841D01*
X56441Y-144000D02*
Y-143200D01*
X56041Y-151600D02*
X56841D01*
X56441Y-152000D02*
Y-151200D01*
X56041Y-191600D02*
X56841D01*
X56441Y-192000D02*
Y-191200D01*
X56041Y-199600D02*
X56841D01*
X56441Y-200000D02*
Y-199200D01*
X56041Y-215600D02*
X56841D01*
X56441Y-216000D02*
Y-215200D01*
X56041Y-223600D02*
X56841D01*
X56441Y-224000D02*
Y-223200D01*
X56041Y-231600D02*
X56841D01*
X56441Y-232000D02*
Y-231200D01*
X56041Y-247600D02*
X56841D01*
X56441Y-248000D02*
Y-247200D01*
X56041Y-255600D02*
X56841D01*
X56441Y-256000D02*
Y-255200D01*
X56041Y-271600D02*
X56841D01*
X56441Y-272000D02*
Y-271200D01*
X56041Y-279600D02*
X56841D01*
X56441Y-280000D02*
Y-279200D01*
X56041Y-287600D02*
X56841D01*
X56441Y-288000D02*
Y-287200D01*
X56041Y-303600D02*
X56841D01*
X56441Y-304000D02*
Y-303200D01*
X56041Y-311600D02*
X56841D01*
X56441Y-312000D02*
Y-311200D01*
X56041Y-327600D02*
X56841D01*
X56441Y-328000D02*
Y-327200D01*
X56041Y-335600D02*
X56841D01*
X56441Y-336000D02*
Y-335200D01*
X56041Y-343600D02*
X56841D01*
X56441Y-344000D02*
Y-343200D01*
X56041Y-351600D02*
X56841D01*
X56441Y-352000D02*
Y-351200D01*
X54041Y-139600D02*
X54841D01*
X54441Y-140000D02*
Y-139200D01*
X52041Y-143600D02*
X52841D01*
X52441Y-144000D02*
Y-143200D01*
X54041Y-147600D02*
X54841D01*
X54441Y-148000D02*
Y-147200D01*
X52041Y-151600D02*
X52841D01*
X52441Y-152000D02*
Y-151200D01*
X52041Y-191600D02*
X52841D01*
X52441Y-192000D02*
Y-191200D01*
X54041Y-195600D02*
X54841D01*
X54441Y-196000D02*
Y-195200D01*
X52041Y-199600D02*
X52841D01*
X52441Y-200000D02*
Y-199200D01*
X54041Y-203600D02*
X54841D01*
X54441Y-204000D02*
Y-203200D01*
X52041Y-215600D02*
X52841D01*
X52441Y-216000D02*
Y-215200D01*
X54041Y-219600D02*
X54841D01*
X54441Y-220000D02*
Y-219200D01*
X52041Y-223600D02*
X52841D01*
X52441Y-224000D02*
Y-223200D01*
X54041Y-227600D02*
X54841D01*
X54441Y-228000D02*
Y-227200D01*
X52041Y-231600D02*
X52841D01*
X52441Y-232000D02*
Y-231200D01*
X54041Y-235600D02*
X54841D01*
X54441Y-236000D02*
Y-235200D01*
X54041Y-243600D02*
X54841D01*
X54441Y-244000D02*
Y-243200D01*
X52041Y-247600D02*
X52841D01*
X52441Y-248000D02*
Y-247200D01*
X54041Y-251600D02*
X54841D01*
X54441Y-252000D02*
Y-251200D01*
X52041Y-255600D02*
X52841D01*
X52441Y-256000D02*
Y-255200D01*
X54041Y-267600D02*
X54841D01*
X54441Y-268000D02*
Y-267200D01*
X52041Y-271600D02*
X52841D01*
X52441Y-272000D02*
Y-271200D01*
X54041Y-275600D02*
X54841D01*
X54441Y-276000D02*
Y-275200D01*
X52041Y-279600D02*
X52841D01*
X52441Y-280000D02*
Y-279200D01*
X52041Y-287600D02*
X52841D01*
X52441Y-288000D02*
Y-287200D01*
X54041Y-291600D02*
X54841D01*
X54441Y-292000D02*
Y-291200D01*
X54041Y-299600D02*
X54841D01*
X54441Y-300000D02*
Y-299200D01*
X52041Y-303600D02*
X52841D01*
X52441Y-304000D02*
Y-303200D01*
X54041Y-307600D02*
X54841D01*
X54441Y-308000D02*
Y-307200D01*
X52041Y-311600D02*
X52841D01*
X52441Y-312000D02*
Y-311200D01*
X54041Y-323600D02*
X54841D01*
X54441Y-324000D02*
Y-323200D01*
X52041Y-327600D02*
X52841D01*
X52441Y-328000D02*
Y-327200D01*
X54041Y-331600D02*
X54841D01*
X54441Y-332000D02*
Y-331200D01*
X52041Y-335600D02*
X52841D01*
X52441Y-336000D02*
Y-335200D01*
X54041Y-339600D02*
X54841D01*
X54441Y-340000D02*
Y-339200D01*
X52041Y-343600D02*
X52841D01*
X52441Y-344000D02*
Y-343200D01*
X52041Y-351600D02*
X52841D01*
X52441Y-352000D02*
Y-351200D01*
X50041Y-139600D02*
X50841D01*
X50441Y-140000D02*
Y-139200D01*
X48041Y-143600D02*
X48841D01*
X48441Y-144000D02*
Y-143200D01*
X50041Y-195600D02*
X50841D01*
X50441Y-196000D02*
Y-195200D01*
X48041Y-199600D02*
X48841D01*
X48441Y-200000D02*
Y-199200D01*
X48041Y-223600D02*
X48841D01*
X48441Y-224000D02*
Y-223200D01*
X50041Y-227600D02*
X50841D01*
X50441Y-228000D02*
Y-227200D01*
X48041Y-231600D02*
X48841D01*
X48441Y-232000D02*
Y-231200D01*
X50041Y-235600D02*
X50841D01*
X50441Y-236000D02*
Y-235200D01*
X50041Y-243600D02*
X50841D01*
X50441Y-244000D02*
Y-243200D01*
X48041Y-247600D02*
X48841D01*
X48441Y-248000D02*
Y-247200D01*
X50041Y-251600D02*
X50841D01*
X50441Y-252000D02*
Y-251200D01*
X50041Y-275600D02*
X50841D01*
X50441Y-276000D02*
Y-275200D01*
X48041Y-279600D02*
X48841D01*
X48441Y-280000D02*
Y-279200D01*
X48041Y-287600D02*
X48841D01*
X48441Y-288000D02*
Y-287200D01*
X50041Y-291600D02*
X50841D01*
X50441Y-292000D02*
Y-291200D01*
X50041Y-299600D02*
X50841D01*
X50441Y-300000D02*
Y-299200D01*
X48041Y-303600D02*
X48841D01*
X48441Y-304000D02*
Y-303200D01*
X50041Y-331600D02*
X50841D01*
X50441Y-332000D02*
Y-331200D01*
X48041Y-335600D02*
X48841D01*
X48441Y-336000D02*
Y-335200D01*
X50041Y-339600D02*
X50841D01*
X50441Y-340000D02*
Y-339200D01*
X48041Y-343600D02*
X48841D01*
X48441Y-344000D02*
Y-343200D01*
X48041Y-351600D02*
X48841D01*
X48441Y-352000D02*
Y-351200D01*
X46041Y-139600D02*
X46841D01*
X46441Y-140000D02*
Y-139200D01*
X44041Y-143600D02*
X44841D01*
X44441Y-144000D02*
Y-143200D01*
X46041Y-227600D02*
X46841D01*
X46441Y-228000D02*
Y-227200D01*
X44041Y-231600D02*
X44841D01*
X44441Y-232000D02*
Y-231200D01*
X46041Y-235600D02*
X46841D01*
X46441Y-236000D02*
Y-235200D01*
X46041Y-243600D02*
X46841D01*
X46441Y-244000D02*
Y-243200D01*
X44041Y-247600D02*
X44841D01*
X44441Y-248000D02*
Y-247200D01*
X44041Y-279600D02*
X44841D01*
X44441Y-280000D02*
Y-279200D01*
X44041Y-287600D02*
X44841D01*
X44441Y-288000D02*
Y-287200D01*
X46041Y-291600D02*
X46841D01*
X46441Y-292000D02*
Y-291200D01*
X46041Y-299600D02*
X46841D01*
X46441Y-300000D02*
Y-299200D01*
X46041Y-331600D02*
X46841D01*
X46441Y-332000D02*
Y-331200D01*
X44041Y-335600D02*
X44841D01*
X44441Y-336000D02*
Y-335200D01*
X46041Y-339600D02*
X46841D01*
X46441Y-340000D02*
Y-339200D01*
X44041Y-343600D02*
X44841D01*
X44441Y-344000D02*
Y-343200D01*
X44041Y-351600D02*
X44841D01*
X44441Y-352000D02*
Y-351200D01*
X42041Y-139600D02*
X42841D01*
X42441Y-140000D02*
Y-139200D01*
X40041Y-143600D02*
X40841D01*
X40441Y-144000D02*
Y-143200D01*
X40041Y-223600D02*
X40841D01*
X40441Y-224000D02*
Y-223200D01*
X42041Y-227600D02*
X42841D01*
X42441Y-228000D02*
Y-227200D01*
X40041Y-231600D02*
X40841D01*
X40441Y-232000D02*
Y-231200D01*
X42041Y-235600D02*
X42841D01*
X42441Y-236000D02*
Y-235200D01*
X42041Y-243600D02*
X42841D01*
X42441Y-244000D02*
Y-243200D01*
X40041Y-247600D02*
X40841D01*
X40441Y-248000D02*
Y-247200D01*
X42041Y-299600D02*
X42841D01*
X42441Y-300000D02*
Y-299200D01*
X42041Y-331600D02*
X42841D01*
X42441Y-332000D02*
Y-331200D01*
X40041Y-335600D02*
X40841D01*
X40441Y-336000D02*
Y-335200D01*
X42041Y-339600D02*
X42841D01*
X42441Y-340000D02*
Y-339200D01*
X40041Y-343600D02*
X40841D01*
X40441Y-344000D02*
Y-343200D01*
X40041Y-351600D02*
X40841D01*
X40441Y-352000D02*
Y-351200D01*
X38041Y-139600D02*
X38841D01*
X38441Y-140000D02*
Y-139200D01*
X36041Y-143600D02*
X36841D01*
X36441Y-144000D02*
Y-143200D01*
X36041Y-151600D02*
X36841D01*
X36441Y-152000D02*
Y-151200D01*
X36041Y-215600D02*
X36841D01*
X36441Y-216000D02*
Y-215200D01*
X36041Y-223600D02*
X36841D01*
X36441Y-224000D02*
Y-223200D01*
X38041Y-227600D02*
X38841D01*
X38441Y-228000D02*
Y-227200D01*
X36041Y-231600D02*
X36841D01*
X36441Y-232000D02*
Y-231200D01*
X38041Y-235600D02*
X38841D01*
X38441Y-236000D02*
Y-235200D01*
X38041Y-243600D02*
X38841D01*
X38441Y-244000D02*
Y-243200D01*
X36041Y-247600D02*
X36841D01*
X36441Y-248000D02*
Y-247200D01*
X38041Y-251600D02*
X38841D01*
X38441Y-252000D02*
Y-251200D01*
X36041Y-255600D02*
X36841D01*
X36441Y-256000D02*
Y-255200D01*
X36041Y-327600D02*
X36841D01*
X36441Y-328000D02*
Y-327200D01*
X38041Y-331600D02*
X38841D01*
X38441Y-332000D02*
Y-331200D01*
X36041Y-335600D02*
X36841D01*
X36441Y-336000D02*
Y-335200D01*
X38041Y-339600D02*
X38841D01*
X38441Y-340000D02*
Y-339200D01*
X36041Y-343600D02*
X36841D01*
X36441Y-344000D02*
Y-343200D01*
X36041Y-351600D02*
X36841D01*
X36441Y-352000D02*
Y-351200D01*
X34041Y-139600D02*
X34841D01*
X34441Y-140000D02*
Y-139200D01*
X32041Y-143600D02*
X32841D01*
X32441Y-144000D02*
Y-143200D01*
X34041Y-147600D02*
X34841D01*
X34441Y-148000D02*
Y-147200D01*
X32041Y-151600D02*
X32841D01*
X32441Y-152000D02*
Y-151200D01*
X34041Y-163600D02*
X34841D01*
X34441Y-164000D02*
Y-163200D01*
X34041Y-219600D02*
X34841D01*
X34441Y-220000D02*
Y-219200D01*
X34041Y-227600D02*
X34841D01*
X34441Y-228000D02*
Y-227200D01*
X34041Y-235600D02*
X34841D01*
X34441Y-236000D02*
Y-235200D01*
X34041Y-243600D02*
X34841D01*
X34441Y-244000D02*
Y-243200D01*
X34041Y-251600D02*
X34841D01*
X34441Y-252000D02*
Y-251200D01*
X34041Y-267600D02*
X34841D01*
X34441Y-268000D02*
Y-267200D01*
X34041Y-275600D02*
X34841D01*
X34441Y-276000D02*
Y-275200D01*
X34041Y-299600D02*
X34841D01*
X34441Y-300000D02*
Y-299200D01*
X34041Y-307600D02*
X34841D01*
X34441Y-308000D02*
Y-307200D01*
X34041Y-323600D02*
X34841D01*
X34441Y-324000D02*
Y-323200D01*
X32041Y-327600D02*
X32841D01*
X32441Y-328000D02*
Y-327200D01*
X34041Y-331600D02*
X34841D01*
X34441Y-332000D02*
Y-331200D01*
X32041Y-335600D02*
X32841D01*
X32441Y-336000D02*
Y-335200D01*
X34041Y-339600D02*
X34841D01*
X34441Y-340000D02*
Y-339200D01*
X32041Y-343600D02*
X32841D01*
X32441Y-344000D02*
Y-343200D01*
X32041Y-351600D02*
X32841D01*
X32441Y-352000D02*
Y-351200D01*
X30041Y-139600D02*
X30841D01*
X30441Y-140000D02*
Y-139200D01*
X28041Y-143600D02*
X28841D01*
X28441Y-144000D02*
Y-143200D01*
X30041Y-147600D02*
X30841D01*
X30441Y-148000D02*
Y-147200D01*
X28041Y-151600D02*
X28841D01*
X28441Y-152000D02*
Y-151200D01*
X30041Y-163600D02*
X30841D01*
X30441Y-164000D02*
Y-163200D01*
X28041Y-167600D02*
X28841D01*
X28441Y-168000D02*
Y-167200D01*
X28041Y-327600D02*
X28841D01*
X28441Y-328000D02*
Y-327200D01*
X30041Y-331600D02*
X30841D01*
X30441Y-332000D02*
Y-331200D01*
X28041Y-335600D02*
X28841D01*
X28441Y-336000D02*
Y-335200D01*
X30041Y-339600D02*
X30841D01*
X30441Y-340000D02*
Y-339200D01*
X28041Y-343600D02*
X28841D01*
X28441Y-344000D02*
Y-343200D01*
X28041Y-351600D02*
X28841D01*
X28441Y-352000D02*
Y-351200D01*
X26041Y-139600D02*
X26841D01*
X26441Y-140000D02*
Y-139200D01*
X24041Y-143600D02*
X24841D01*
X24441Y-144000D02*
Y-143200D01*
X26041Y-147600D02*
X26841D01*
X26441Y-148000D02*
Y-147200D01*
X24041Y-151600D02*
X24841D01*
X24441Y-152000D02*
Y-151200D01*
X26041Y-163600D02*
X26841D01*
X26441Y-164000D02*
Y-163200D01*
X24041Y-167600D02*
X24841D01*
X24441Y-168000D02*
Y-167200D01*
X24041Y-191600D02*
X24841D01*
X24441Y-192000D02*
Y-191200D01*
X26041Y-195600D02*
X26841D01*
X26441Y-196000D02*
Y-195200D01*
X24041Y-287600D02*
X24841D01*
X24441Y-288000D02*
Y-287200D01*
X26041Y-299600D02*
X26841D01*
X26441Y-300000D02*
Y-299200D01*
X24041Y-303600D02*
X24841D01*
X24441Y-304000D02*
Y-303200D01*
X26041Y-307600D02*
X26841D01*
X26441Y-308000D02*
Y-307200D01*
X24041Y-311600D02*
X24841D01*
X24441Y-312000D02*
Y-311200D01*
X26041Y-331600D02*
X26841D01*
X26441Y-332000D02*
Y-331200D01*
X24041Y-335600D02*
X24841D01*
X24441Y-336000D02*
Y-335200D01*
X26041Y-339600D02*
X26841D01*
X26441Y-340000D02*
Y-339200D01*
X24041Y-343600D02*
X24841D01*
X24441Y-344000D02*
Y-343200D01*
X24041Y-351600D02*
X24841D01*
X24441Y-352000D02*
Y-351200D01*
X22041Y-139600D02*
X22841D01*
X22441Y-140000D02*
Y-139200D01*
X20041Y-143600D02*
X20841D01*
X20441Y-144000D02*
Y-143200D01*
X22041Y-147600D02*
X22841D01*
X22441Y-148000D02*
Y-147200D01*
X20041Y-151600D02*
X20841D01*
X20441Y-152000D02*
Y-151200D01*
X22041Y-163600D02*
X22841D01*
X22441Y-164000D02*
Y-163200D01*
X20041Y-167600D02*
X20841D01*
X20441Y-168000D02*
Y-167200D01*
X22041Y-171600D02*
X22841D01*
X22441Y-172000D02*
Y-171200D01*
X20041Y-191600D02*
X20841D01*
X20441Y-192000D02*
Y-191200D01*
X22041Y-195600D02*
X22841D01*
X22441Y-196000D02*
Y-195200D01*
X20041Y-199600D02*
X20841D01*
X20441Y-200000D02*
Y-199200D01*
X20041Y-231600D02*
X20841D01*
X20441Y-232000D02*
Y-231200D01*
X22041Y-235600D02*
X22841D01*
X22441Y-236000D02*
Y-235200D01*
X22041Y-243600D02*
X22841D01*
X22441Y-244000D02*
Y-243200D01*
X20041Y-247600D02*
X20841D01*
X20441Y-248000D02*
Y-247200D01*
X22041Y-251600D02*
X22841D01*
X22441Y-252000D02*
Y-251200D01*
X20041Y-255600D02*
X20841D01*
X20441Y-256000D02*
Y-255200D01*
X22041Y-259600D02*
X22841D01*
X22441Y-260000D02*
Y-259200D01*
X22041Y-267600D02*
X22841D01*
X22441Y-268000D02*
Y-267200D01*
X20041Y-271600D02*
X20841D01*
X20441Y-272000D02*
Y-271200D01*
X22041Y-283600D02*
X22841D01*
X22441Y-284000D02*
Y-283200D01*
X20041Y-287600D02*
X20841D01*
X20441Y-288000D02*
Y-287200D01*
X22041Y-291600D02*
X22841D01*
X22441Y-292000D02*
Y-291200D01*
X22041Y-299600D02*
X22841D01*
X22441Y-300000D02*
Y-299200D01*
X20041Y-303600D02*
X20841D01*
X20441Y-304000D02*
Y-303200D01*
X22041Y-307600D02*
X22841D01*
X22441Y-308000D02*
Y-307200D01*
X20041Y-311600D02*
X20841D01*
X20441Y-312000D02*
Y-311200D01*
X22041Y-323600D02*
X22841D01*
X22441Y-324000D02*
Y-323200D01*
X20041Y-335600D02*
X20841D01*
X20441Y-336000D02*
Y-335200D01*
X22041Y-339600D02*
X22841D01*
X22441Y-340000D02*
Y-339200D01*
X20041Y-343600D02*
X20841D01*
X20441Y-344000D02*
Y-343200D01*
X20041Y-351600D02*
X20841D01*
X20441Y-352000D02*
Y-351200D01*
X18041Y-139600D02*
X18841D01*
X18441Y-140000D02*
Y-139200D01*
X16041Y-143600D02*
X16841D01*
X16441Y-144000D02*
Y-143200D01*
X18041Y-147600D02*
X18841D01*
X18441Y-148000D02*
Y-147200D01*
X16041Y-151600D02*
X16841D01*
X16441Y-152000D02*
Y-151200D01*
X18041Y-163600D02*
X18841D01*
X18441Y-164000D02*
Y-163200D01*
X16041Y-167600D02*
X16841D01*
X16441Y-168000D02*
Y-167200D01*
X18041Y-171600D02*
X18841D01*
X18441Y-172000D02*
Y-171200D01*
X16041Y-191600D02*
X16841D01*
X16441Y-192000D02*
Y-191200D01*
X18041Y-195600D02*
X18841D01*
X18441Y-196000D02*
Y-195200D01*
X16041Y-199600D02*
X16841D01*
X16441Y-200000D02*
Y-199200D01*
X18041Y-203600D02*
X18841D01*
X18441Y-204000D02*
Y-203200D01*
X16041Y-215600D02*
X16841D01*
X16441Y-216000D02*
Y-215200D01*
X18041Y-219600D02*
X18841D01*
X18441Y-220000D02*
Y-219200D01*
X16041Y-223600D02*
X16841D01*
X16441Y-224000D02*
Y-223200D01*
X18041Y-235600D02*
X18841D01*
X18441Y-236000D02*
Y-235200D01*
X18041Y-243600D02*
X18841D01*
X18441Y-244000D02*
Y-243200D01*
X16041Y-247600D02*
X16841D01*
X16441Y-248000D02*
Y-247200D01*
X18041Y-251600D02*
X18841D01*
X18441Y-252000D02*
Y-251200D01*
X16041Y-255600D02*
X16841D01*
X16441Y-256000D02*
Y-255200D01*
X18041Y-259600D02*
X18841D01*
X18441Y-260000D02*
Y-259200D01*
X18041Y-267600D02*
X18841D01*
X18441Y-268000D02*
Y-267200D01*
X16041Y-271600D02*
X16841D01*
X16441Y-272000D02*
Y-271200D01*
X18041Y-275600D02*
X18841D01*
X18441Y-276000D02*
Y-275200D01*
X16041Y-279600D02*
X16841D01*
X16441Y-280000D02*
Y-279200D01*
X18041Y-291600D02*
X18841D01*
X18441Y-292000D02*
Y-291200D01*
X18041Y-299600D02*
X18841D01*
X18441Y-300000D02*
Y-299200D01*
X16041Y-303600D02*
X16841D01*
X16441Y-304000D02*
Y-303200D01*
X18041Y-307600D02*
X18841D01*
X18441Y-308000D02*
Y-307200D01*
X16041Y-311600D02*
X16841D01*
X16441Y-312000D02*
Y-311200D01*
X18041Y-323600D02*
X18841D01*
X18441Y-324000D02*
Y-323200D01*
X16041Y-327600D02*
X16841D01*
X16441Y-328000D02*
Y-327200D01*
X18041Y-339600D02*
X18841D01*
X18441Y-340000D02*
Y-339200D01*
X16041Y-343600D02*
X16841D01*
X16441Y-344000D02*
Y-343200D01*
X16041Y-351600D02*
X16841D01*
X16441Y-352000D02*
Y-351200D01*
X14041Y-139600D02*
X14841D01*
X14441Y-140000D02*
Y-139200D01*
X12041Y-143600D02*
X12841D01*
X12441Y-144000D02*
Y-143200D01*
X14041Y-147600D02*
X14841D01*
X14441Y-148000D02*
Y-147200D01*
X12041Y-151600D02*
X12841D01*
X12441Y-152000D02*
Y-151200D01*
X14041Y-163600D02*
X14841D01*
X14441Y-164000D02*
Y-163200D01*
X12041Y-167600D02*
X12841D01*
X12441Y-168000D02*
Y-167200D01*
X14041Y-171600D02*
X14841D01*
X14441Y-172000D02*
Y-171200D01*
X12041Y-191600D02*
X12841D01*
X12441Y-192000D02*
Y-191200D01*
X14041Y-195600D02*
X14841D01*
X14441Y-196000D02*
Y-195200D01*
X12041Y-199600D02*
X12841D01*
X12441Y-200000D02*
Y-199200D01*
X14041Y-203600D02*
X14841D01*
X14441Y-204000D02*
Y-203200D01*
X12041Y-215600D02*
X12841D01*
X12441Y-216000D02*
Y-215200D01*
X14041Y-219600D02*
X14841D01*
X14441Y-220000D02*
Y-219200D01*
X12041Y-223600D02*
X12841D01*
X12441Y-224000D02*
Y-223200D01*
X14041Y-243600D02*
X14841D01*
X14441Y-244000D02*
Y-243200D01*
X12041Y-247600D02*
X12841D01*
X12441Y-248000D02*
Y-247200D01*
X14041Y-251600D02*
X14841D01*
X14441Y-252000D02*
Y-251200D01*
X12041Y-255600D02*
X12841D01*
X12441Y-256000D02*
Y-255200D01*
X14041Y-259600D02*
X14841D01*
X14441Y-260000D02*
Y-259200D01*
X14041Y-267600D02*
X14841D01*
X14441Y-268000D02*
Y-267200D01*
X12041Y-271600D02*
X12841D01*
X12441Y-272000D02*
Y-271200D01*
X14041Y-275600D02*
X14841D01*
X14441Y-276000D02*
Y-275200D01*
X12041Y-279600D02*
X12841D01*
X12441Y-280000D02*
Y-279200D01*
X14041Y-291600D02*
X14841D01*
X14441Y-292000D02*
Y-291200D01*
X14041Y-299600D02*
X14841D01*
X14441Y-300000D02*
Y-299200D01*
X12041Y-303600D02*
X12841D01*
X12441Y-304000D02*
Y-303200D01*
X14041Y-307600D02*
X14841D01*
X14441Y-308000D02*
Y-307200D01*
X12041Y-311600D02*
X12841D01*
X12441Y-312000D02*
Y-311200D01*
X14041Y-323600D02*
X14841D01*
X14441Y-324000D02*
Y-323200D01*
X12041Y-327600D02*
X12841D01*
X12441Y-328000D02*
Y-327200D01*
X14041Y-331600D02*
X14841D01*
X14441Y-332000D02*
Y-331200D01*
X12041Y-343600D02*
X12841D01*
X12441Y-344000D02*
Y-343200D01*
X12041Y-351600D02*
X12841D01*
X12441Y-352000D02*
Y-351200D01*
X10041Y-139600D02*
X10841D01*
X10441Y-140000D02*
Y-139200D01*
X10041Y-163600D02*
X10841D01*
X10441Y-164000D02*
Y-163200D01*
X10041Y-171600D02*
X10841D01*
X10441Y-172000D02*
Y-171200D01*
X8041Y-191600D02*
X8841D01*
X8441Y-192000D02*
Y-191200D01*
X10041Y-195600D02*
X10841D01*
X10441Y-196000D02*
Y-195200D01*
X10041Y-203600D02*
X10841D01*
X10441Y-204000D02*
Y-203200D01*
X10041Y-227600D02*
X10841D01*
X10441Y-228000D02*
Y-227200D01*
X10041Y-243600D02*
X10841D01*
X10441Y-244000D02*
Y-243200D01*
X8041Y-247600D02*
X8841D01*
X8441Y-248000D02*
Y-247200D01*
X10041Y-251600D02*
X10841D01*
X10441Y-252000D02*
Y-251200D01*
X10041Y-259600D02*
X10841D01*
X10441Y-260000D02*
Y-259200D01*
X10041Y-267600D02*
X10841D01*
X10441Y-268000D02*
Y-267200D01*
X10041Y-275600D02*
X10841D01*
X10441Y-276000D02*
Y-275200D01*
X8041Y-279600D02*
X8841D01*
X8441Y-280000D02*
Y-279200D01*
X10041Y-299600D02*
X10841D01*
X10441Y-300000D02*
Y-299200D01*
X10041Y-323600D02*
X10841D01*
X10441Y-324000D02*
Y-323200D01*
X10041Y-331600D02*
X10841D01*
X10441Y-332000D02*
Y-331200D01*
X8041Y-351600D02*
X8841D01*
X8441Y-352000D02*
Y-351200D01*
X6041Y-139600D02*
X6841D01*
X6441Y-140000D02*
Y-139200D01*
X4041Y-191600D02*
X4841D01*
X4441Y-192000D02*
Y-191200D01*
X6041Y-243600D02*
X6841D01*
X6441Y-244000D02*
Y-243200D01*
X4041Y-351600D02*
X4841D01*
X4441Y-352000D02*
Y-351200D01*
X2041Y-243600D02*
X2841D01*
X2441Y-244000D02*
Y-243200D01*
X41Y-351600D02*
X841D01*
X441Y-352000D02*
Y-351200D01*
X-3959Y-191600D02*
X-3159D01*
X-3559Y-192000D02*
Y-191200D01*
X-1959Y-243600D02*
X-1159D01*
X-1559Y-244000D02*
Y-243200D01*
X-3959Y-351600D02*
X-3159D01*
X-3559Y-352000D02*
Y-351200D01*
X-5959Y-139600D02*
X-5159D01*
X-5559Y-140000D02*
Y-139200D01*
X-7959Y-143600D02*
X-7159D01*
X-7559Y-144000D02*
Y-143200D01*
X-7959Y-167600D02*
X-7159D01*
X-7559Y-168000D02*
Y-167200D01*
X-7959Y-191600D02*
X-7159D01*
X-7559Y-192000D02*
Y-191200D01*
X-7959Y-199600D02*
X-7159D01*
X-7559Y-200000D02*
Y-199200D01*
X-7959Y-223600D02*
X-7159D01*
X-7559Y-224000D02*
Y-223200D01*
X-5959Y-227600D02*
X-5159D01*
X-5559Y-228000D02*
Y-227200D01*
X-5959Y-243600D02*
X-5159D01*
X-5559Y-244000D02*
Y-243200D01*
X-7959Y-247600D02*
X-7159D01*
X-7559Y-248000D02*
Y-247200D01*
X-7959Y-279600D02*
X-7159D01*
X-7559Y-280000D02*
Y-279200D01*
X-5959Y-299600D02*
X-5159D01*
X-5559Y-300000D02*
Y-299200D01*
X-7959Y-303600D02*
X-7159D01*
X-7559Y-304000D02*
Y-303200D01*
X-7959Y-327600D02*
X-7159D01*
X-7559Y-328000D02*
Y-327200D01*
X-7959Y-351600D02*
X-7159D01*
X-7559Y-352000D02*
Y-351200D01*
X-9959Y-139600D02*
X-9159D01*
X-9559Y-140000D02*
Y-139200D01*
X-9959Y-171600D02*
X-9159D01*
X-9559Y-172000D02*
Y-171200D01*
X-11959Y-191600D02*
X-11159D01*
X-11559Y-192000D02*
Y-191200D01*
X-9959Y-195600D02*
X-9159D01*
X-9559Y-196000D02*
Y-195200D01*
X-9959Y-227600D02*
X-9159D01*
X-9559Y-228000D02*
Y-227200D01*
X-9959Y-243600D02*
X-9159D01*
X-9559Y-244000D02*
Y-243200D01*
X-11959Y-247600D02*
X-11159D01*
X-11559Y-248000D02*
Y-247200D01*
X-9959Y-251600D02*
X-9159D01*
X-9559Y-252000D02*
Y-251200D01*
X-9959Y-275600D02*
X-9159D01*
X-9559Y-276000D02*
Y-275200D01*
X-11959Y-279600D02*
X-11159D01*
X-11559Y-280000D02*
Y-279200D01*
X-9959Y-299600D02*
X-9159D01*
X-9559Y-300000D02*
Y-299200D01*
X-9959Y-331600D02*
X-9159D01*
X-9559Y-332000D02*
Y-331200D01*
X-11959Y-351600D02*
X-11159D01*
X-11559Y-352000D02*
Y-351200D01*
X-13959Y-139600D02*
X-13159D01*
X-13559Y-140000D02*
Y-139200D01*
X-15959Y-191600D02*
X-15159D01*
X-15559Y-192000D02*
Y-191200D01*
X-13959Y-243600D02*
X-13159D01*
X-13559Y-244000D02*
Y-243200D01*
X-15959Y-351600D02*
X-15159D01*
X-15559Y-352000D02*
Y-351200D01*
X-19959Y-263600D02*
X-19159D01*
X-19559Y-264000D02*
Y-263200D01*
X-19959Y-351600D02*
X-19159D01*
X-19559Y-352000D02*
Y-351200D01*
X-23959Y-159600D02*
X-23159D01*
X-23559Y-160000D02*
Y-159200D01*
X-23959Y-191600D02*
X-23159D01*
X-23559Y-192000D02*
Y-191200D01*
X-21959Y-211600D02*
X-21159D01*
X-21559Y-212000D02*
Y-211200D01*
X-23959Y-263600D02*
X-23159D01*
X-23559Y-264000D02*
Y-263200D01*
X-21959Y-315600D02*
X-21159D01*
X-21559Y-316000D02*
Y-315200D01*
X-23959Y-351600D02*
X-23159D01*
X-23559Y-352000D02*
Y-351200D01*
X-25959Y-139600D02*
X-25159D01*
X-25559Y-140000D02*
Y-139200D01*
X-25959Y-155600D02*
X-25159D01*
X-25559Y-156000D02*
Y-155200D01*
X-25959Y-211600D02*
X-25159D01*
X-25559Y-212000D02*
Y-211200D01*
X-25959Y-259600D02*
X-25159D01*
X-25559Y-260000D02*
Y-259200D01*
X-25959Y-267600D02*
X-25159D01*
X-25559Y-268000D02*
Y-267200D01*
X-25959Y-299600D02*
X-25159D01*
X-25559Y-300000D02*
Y-299200D01*
X-25959Y-315600D02*
X-25159D01*
X-25559Y-316000D02*
Y-315200D01*
X269285Y-136843D02*
X270085D01*
X269685Y-137242D02*
Y-136442D01*
X233852Y-133742D02*
X234652D01*
X234252Y-134142D02*
Y-133342D01*
X263380Y-106151D02*
X264179D01*
X263779Y-106551D02*
Y-105751D01*
X71450Y-147638D02*
X72250D01*
X71850Y-148038D02*
Y-147238D01*
X75387Y-131890D02*
X76187D01*
X75787Y-132290D02*
Y-131490D01*
X643301Y-63976D02*
X644101D01*
X643701Y-64376D02*
Y-63576D01*
X644285Y-45276D02*
X645085D01*
X644685Y-45676D02*
Y-44876D01*
X622600Y-37402D02*
X623400D01*
X623000Y-37802D02*
Y-37002D01*
X609836Y-8858D02*
X610636D01*
X610236Y-9258D02*
Y-8458D01*
X608852Y-26575D02*
X609652D01*
X609252Y-26975D02*
Y-26175D01*
X98025Y-102362D02*
X98825D01*
X98425Y-102762D02*
Y-101962D01*
X89167Y-102362D02*
X89967D01*
X89567Y-102762D02*
Y-101962D01*
X85230Y-313976D02*
X86030D01*
X85630Y-314376D02*
Y-313576D01*
X86214Y-258858D02*
X87014D01*
X86614Y-259258D02*
Y-258458D01*
X81293Y-205709D02*
X82093D01*
X81693Y-206109D02*
Y-205309D01*
X86214Y-110236D02*
X87014D01*
X86614Y-110636D02*
Y-109836D01*
X359836Y-268586D02*
X360636D01*
X360236Y-268986D02*
Y-268186D01*
X359836Y-272490D02*
X360636D01*
X360236Y-272890D02*
Y-272090D01*
X63576Y-227362D02*
X64376D01*
X63976Y-227762D02*
Y-226962D01*
X68498Y-285433D02*
X69298D01*
X68898Y-285833D02*
Y-285033D01*
X67513Y-340551D02*
X68313D01*
X67913Y-340951D02*
Y-340151D01*
X68173Y-179321D02*
X68973D01*
X68573Y-179721D02*
Y-178921D01*
X43891Y-252953D02*
X44691D01*
X44291Y-253353D02*
Y-252553D01*
X43891Y-272638D02*
X44691D01*
X44291Y-273038D02*
Y-272238D01*
X43891Y-326772D02*
X44691D01*
X44291Y-327172D02*
Y-326372D01*
X43891Y-307087D02*
X44691D01*
X44291Y-307487D02*
Y-306687D01*
X26175Y-291339D02*
X26975D01*
X26575Y-291739D02*
Y-290939D01*
X31096Y-189961D02*
X31896D01*
X31496Y-190361D02*
Y-189561D01*
X43891Y-147638D02*
X44691D01*
X44291Y-148038D02*
Y-147238D01*
X43891Y-167323D02*
X44691D01*
X44291Y-167723D02*
Y-166923D01*
X43891Y-200787D02*
X44691D01*
X44291Y-201187D02*
Y-200387D01*
X43891Y-220472D02*
X44691D01*
X44291Y-220872D02*
Y-220072D01*
X570328Y-105662D02*
X571128D01*
X570727Y-106062D02*
Y-105262D01*
X325387Y-243205D02*
X326187D01*
X325787Y-243605D02*
Y-242805D01*
X325387Y-233362D02*
X326187D01*
X325787Y-233762D02*
Y-232962D01*
X103009Y-141732D02*
X103809D01*
X103409Y-142132D02*
Y-141332D01*
X102946Y-110236D02*
X103746D01*
X103347Y-110636D02*
Y-109836D01*
X118694Y-126047D02*
X119494D01*
X119095Y-126447D02*
Y-125647D01*
X493694Y-137647D02*
X494494D01*
X494095Y-138047D02*
Y-137247D01*
X518301Y-104214D02*
X519101D01*
X518701Y-104614D02*
Y-103814D01*
X519187Y-134596D02*
X519987D01*
X519587Y-134996D02*
Y-134196D01*
X528143Y-104214D02*
X528943D01*
X528543Y-104614D02*
Y-103814D01*
X624600Y-48080D02*
X625400D01*
X625000Y-48480D02*
Y-47680D01*
X658065Y-21899D02*
X658865D01*
X658465Y-22299D02*
Y-21499D01*
X624600Y-29773D02*
X625400D01*
X625000Y-30173D02*
Y-29373D01*
X113773Y-83088D02*
X114573D01*
X114173Y-83488D02*
Y-82688D01*
X441529Y-122883D02*
X442329D01*
X441929Y-123284D02*
Y-122484D01*
X256490Y-124852D02*
X257290D01*
X256890Y-125252D02*
Y-124452D01*
X256490Y-121899D02*
X257290D01*
X256890Y-122299D02*
Y-121499D01*
X249600Y-120915D02*
X250400D01*
X250000Y-121315D02*
Y-120515D01*
X129521Y-79576D02*
X130321D01*
X129921Y-79976D02*
Y-79176D01*
X473025Y-125836D02*
X473825D01*
X473425Y-126236D02*
Y-125436D01*
X473025Y-123868D02*
X473825D01*
X473425Y-124268D02*
Y-123468D01*
X473025Y-121899D02*
X473825D01*
X473425Y-122299D02*
Y-121499D01*
X505506Y-137647D02*
X506306D01*
X505905Y-138047D02*
Y-137247D01*
X162671Y-390730D02*
X163471D01*
X163071Y-391130D02*
Y-390330D01*
X632031Y-132480D02*
X632831D01*
X632432Y-132880D02*
Y-132080D01*
X613921Y-118307D02*
X614721D01*
X614321Y-118707D02*
Y-117907D01*
X99010Y-50049D02*
X99809D01*
X99410Y-50449D02*
Y-49649D01*
X26095Y-8991D02*
X26895D01*
X26495Y-9391D02*
Y-8591D01*
X512257Y-270462D02*
X513057D01*
X512657Y-270862D02*
Y-270062D01*
X632031Y-141142D02*
X632831D01*
X632432Y-141542D02*
Y-140742D01*
X258885Y-390247D02*
X259685D01*
X259285Y-390647D02*
Y-389847D01*
X266804Y-390009D02*
X267604D01*
X267204Y-390409D02*
Y-389610D01*
X215762Y-390947D02*
X216562D01*
X216162Y-391347D02*
Y-390547D01*
X234744Y-390416D02*
X235544D01*
X235144Y-390816D02*
Y-390016D01*
X251056Y-390009D02*
X251856D01*
X251456Y-390409D02*
Y-389610D01*
X225663Y-390722D02*
X226463D01*
X226063Y-391122D02*
Y-390322D01*
X280801Y-390009D02*
X281601D01*
X281201Y-390409D02*
Y-389610D01*
X174541Y-390600D02*
X175341D01*
X174941Y-391000D02*
Y-390200D01*
X202041Y-390600D02*
X202841D01*
X202441Y-391000D02*
Y-390200D01*
X538413Y-144506D02*
X539213D01*
X538813Y-144905D02*
Y-144106D01*
X544413Y-109806D02*
X545213D01*
X544813Y-110205D02*
Y-109406D01*
X566413Y-132405D02*
X567213D01*
X566813Y-132806D02*
Y-132006D01*
X598265Y-223031D02*
X599865D01*
X599065Y-223832D02*
Y-222232D01*
X554964Y-249410D02*
X555764D01*
X555364Y-249810D02*
Y-249009D01*
X543891Y-199655D02*
X544691D01*
X544291Y-200055D02*
Y-199255D01*
X509443Y-197687D02*
X510243D01*
X509842Y-198087D02*
Y-197287D01*
X543891Y-201624D02*
X544691D01*
X544291Y-202024D02*
Y-201224D01*
X509443Y-199655D02*
X510243D01*
X509842Y-200055D02*
Y-199255D01*
X509443Y-201624D02*
X510243D01*
X509842Y-202024D02*
Y-201224D01*
X543891Y-197687D02*
X544691D01*
X544291Y-198087D02*
Y-197287D01*
X509443Y-195718D02*
X510243D01*
X509842Y-196118D02*
Y-195318D01*
X361411Y-207087D02*
X362211D01*
X361811Y-207487D02*
Y-206687D01*
X361017Y-203150D02*
X361817D01*
X361417Y-203550D02*
Y-202750D01*
X326569Y-197573D02*
X327368D01*
X326969Y-197973D02*
Y-197173D01*
X326566Y-195171D02*
X327366D01*
X326966Y-195571D02*
Y-194771D01*
X366135Y-202362D02*
X366935D01*
X366535Y-202762D02*
Y-201962D01*
X358261Y-194488D02*
X359061D01*
X358661Y-194888D02*
Y-194088D01*
X633852Y-314567D02*
X634652D01*
X634252Y-314967D02*
Y-314167D01*
X652750Y-314567D02*
X653550D01*
X653150Y-314967D02*
Y-314167D01*
X508991Y-350636D02*
X509791D01*
X509391Y-351036D02*
Y-350236D01*
X508597Y-335675D02*
X509397D01*
X508997Y-336075D02*
Y-335275D01*
X237002Y-133465D02*
X237802D01*
X237402Y-133865D02*
Y-133065D01*
X240545Y-133465D02*
X241345D01*
X240945Y-133865D02*
Y-133065D01*
X678780Y0D02*
X691299D01*
X685039Y-6260D02*
Y6260D01*
X678780Y-340551D02*
X691299D01*
X685039Y-346811D02*
Y-334291D01*
X446844Y-324852D02*
X447644D01*
X447244Y-325252D02*
Y-324452D01*
X450781Y-324852D02*
X451581D01*
X451181Y-325252D02*
Y-324452D01*
X433458Y-324852D02*
X434258D01*
X433858Y-325252D02*
Y-324452D01*
X460230Y-324852D02*
X461030D01*
X460630Y-325252D02*
Y-324452D01*
X437395Y-324852D02*
X438195D01*
X437795Y-325252D02*
Y-324452D01*
X430702Y-324852D02*
X431502D01*
X431102Y-325252D02*
Y-324452D01*
X444088Y-324852D02*
X444888D01*
X444488Y-325252D02*
Y-324452D01*
X457080Y-324852D02*
X457880D01*
X457480Y-325252D02*
Y-324452D01*
X453537Y-324852D02*
X454337D01*
X453937Y-325252D02*
Y-324452D01*
X440151Y-324852D02*
X440951D01*
X440551Y-325252D02*
Y-324452D01*
X479961Y-340551D02*
X492480D01*
X486221Y-346811D02*
Y-334291D01*
X222238Y-374655D02*
X223038D01*
X222638Y-375055D02*
Y-374255D01*
X218045Y-374108D02*
X218845D01*
X218445Y-374507D02*
Y-373708D01*
X453537Y-306742D02*
X454337D01*
X453937Y-307142D02*
Y-306342D01*
X450781Y-306742D02*
X451581D01*
X451181Y-307142D02*
Y-306342D01*
X266886Y-130697D02*
X267686D01*
X267286Y-131097D02*
Y-130297D01*
X109009Y-140111D02*
X109809D01*
X109409Y-140511D02*
Y-139711D01*
X105009Y-140111D02*
X105809D01*
X105409Y-140511D02*
Y-139711D01*
X101010Y-140111D02*
X101810D01*
X101409Y-140511D02*
Y-139711D01*
X97009Y-140111D02*
X97809D01*
X97409Y-140511D02*
Y-139711D01*
X399218Y-136828D02*
X400018D01*
X399618Y-137228D02*
Y-136428D01*
X65545Y-57923D02*
X66345D01*
X65945Y-58323D02*
Y-57523D01*
X614757Y-8858D02*
X615557D01*
X615158Y-9258D02*
Y-8458D01*
X70466Y-122047D02*
X71266D01*
X70866Y-122447D02*
Y-121647D01*
X359804Y-252984D02*
X360604D01*
X360204Y-253384D02*
Y-252584D01*
X417196Y-175197D02*
X417996D01*
X417596Y-175597D02*
Y-174797D01*
X377521Y-203740D02*
X378321D01*
X377921Y-204140D02*
Y-203340D01*
X371616Y-200787D02*
X372416D01*
X372016Y-201187D02*
Y-200387D01*
X354141Y-223636D02*
X354941D01*
X354541Y-224036D02*
Y-223236D01*
X354052Y-235236D02*
X354852D01*
X354452Y-235636D02*
Y-234836D01*
X356178Y-225247D02*
X356978D01*
X356578Y-225647D02*
Y-224847D01*
X379521Y-201740D02*
X380321D01*
X379921Y-202140D02*
Y-201340D01*
X102128Y-211583D02*
X102928D01*
X102528Y-211983D02*
Y-211183D01*
X96725Y-219488D02*
X97525D01*
X97125Y-219888D02*
Y-219088D01*
X99010Y-216535D02*
X99809D01*
X99410Y-216935D02*
Y-216135D01*
X100978Y-214567D02*
X101778D01*
X101378Y-214967D02*
Y-214167D01*
X86214Y-175197D02*
X87014D01*
X86614Y-175597D02*
Y-174797D01*
X361252Y-235205D02*
X362052D01*
X361652Y-235605D02*
Y-234805D01*
X358731Y-223425D02*
X359531D01*
X359131Y-223825D02*
Y-223025D01*
X361131Y-223425D02*
X361931D01*
X361531Y-223825D02*
Y-223025D01*
X359836Y-262186D02*
X360636D01*
X360236Y-262586D02*
Y-261786D01*
X359836Y-266186D02*
X360636D01*
X360236Y-266586D02*
Y-265786D01*
X85016Y-317699D02*
X85816D01*
X85416Y-318099D02*
Y-317299D01*
X85230Y-263779D02*
X86030D01*
X85630Y-264179D02*
Y-263380D01*
X86162Y-211183D02*
X86962D01*
X86562Y-211583D02*
Y-210783D01*
X410643Y-174974D02*
X411443D01*
X411043Y-175374D02*
Y-174574D01*
X413039Y-174850D02*
X413839D01*
X413440Y-175250D02*
Y-174450D01*
X421196Y-175034D02*
X421996D01*
X421596Y-175434D02*
Y-174634D01*
X406128Y-157767D02*
X406928D01*
X406528Y-158167D02*
Y-157367D01*
X404128Y-163386D02*
X404928D01*
X404528Y-163786D02*
Y-162986D01*
X407080Y-160433D02*
X407880D01*
X407480Y-160833D02*
Y-160033D01*
X86214Y-221457D02*
X87014D01*
X86614Y-221857D02*
Y-221057D01*
X426765Y-175246D02*
X427565D01*
X427165Y-175646D02*
Y-174846D01*
X75387Y-232283D02*
X76187D01*
X75787Y-232683D02*
Y-231884D01*
X86767Y-166377D02*
X87567D01*
X87167Y-166777D02*
Y-165977D01*
X89167Y-166370D02*
X89967D01*
X89567Y-166770D02*
Y-165970D01*
X85230Y-213583D02*
X86030D01*
X85630Y-213983D02*
Y-213183D01*
X85230Y-266179D02*
X86030D01*
X85630Y-266580D02*
Y-265779D01*
X85230Y-320313D02*
X86030D01*
X85630Y-320713D02*
Y-319913D01*
X542876Y-226591D02*
X543676D01*
X543276Y-226991D02*
Y-226191D01*
X543894Y-224248D02*
X544694D01*
X544294Y-224648D02*
Y-223848D01*
X543891Y-233268D02*
X544691D01*
X544291Y-233668D02*
Y-232868D01*
X358852Y-235236D02*
X359652D01*
X359252Y-235636D02*
Y-234836D01*
X356452Y-235236D02*
X357252D01*
X356852Y-235636D02*
Y-234836D01*
X407080Y-163386D02*
X407880D01*
X407480Y-163786D02*
Y-162986D01*
X46844Y-8858D02*
X47644D01*
X47244Y-9258D02*
Y-8458D01*
X39954Y-8858D02*
X40754D01*
X40354Y-9258D02*
Y-8458D01*
X33065Y-8858D02*
X33865D01*
X33465Y-9258D02*
Y-8458D01*
X26175Y19685D02*
X26975D01*
X26575Y19285D02*
Y20085D01*
X86214Y-227362D02*
X87014D01*
X86614Y-227762D02*
Y-226962D01*
X63576Y-221457D02*
X64376D01*
X63976Y-221857D02*
Y-221057D01*
X82277Y-232283D02*
X83077D01*
X82677Y-232683D02*
Y-231884D01*
X63576Y-275590D02*
X64376D01*
X63976Y-275991D02*
Y-275190D01*
X75387Y-285433D02*
X76187D01*
X75787Y-285833D02*
Y-285033D01*
X87198Y-275590D02*
X87998D01*
X87598Y-275991D02*
Y-275190D01*
X87198Y-281496D02*
X87998D01*
X87598Y-281896D02*
Y-281096D01*
X81480Y-287582D02*
X82280D01*
X81880Y-287982D02*
Y-287182D01*
X62592Y-329724D02*
X63392D01*
X62992Y-330124D02*
Y-329324D01*
X74403Y-339567D02*
X75203D01*
X74803Y-339967D02*
Y-339167D01*
X78340Y-340551D02*
X79140D01*
X78740Y-340951D02*
Y-340151D01*
X87198Y-335630D02*
X87998D01*
X87598Y-336030D02*
Y-335230D01*
X87198Y-329724D02*
X87998D01*
X87598Y-330124D02*
Y-329324D01*
X63576Y-179134D02*
X64376D01*
X63976Y-179534D02*
Y-178734D01*
X74403Y-179134D02*
X75203D01*
X74803Y-179534D02*
Y-178734D01*
X86162Y-169257D02*
X86962D01*
X86562Y-169657D02*
Y-168857D01*
X80309Y-180118D02*
X81109D01*
X80709Y-180518D02*
Y-179718D01*
X26175Y-283465D02*
X26975D01*
X26575Y-283865D02*
Y-283065D01*
X30112Y-170276D02*
X30912D01*
X30512Y-170676D02*
Y-169876D01*
X323450Y-241173D02*
X324250D01*
X323850Y-241573D02*
Y-240773D01*
X323450Y-237205D02*
X324250D01*
X323850Y-237605D02*
Y-236805D01*
X323419Y-231299D02*
X324219D01*
X323819Y-231699D02*
Y-230899D01*
X325387Y-229362D02*
X326187D01*
X325787Y-229762D02*
Y-228962D01*
X323419Y-227362D02*
X324219D01*
X323819Y-227762D02*
Y-226962D01*
X325387Y-239205D02*
X326187D01*
X325787Y-239605D02*
Y-238805D01*
X-24022Y-342520D02*
X-23222D01*
X-23622Y-342920D02*
Y-342120D01*
X89167Y-140270D02*
X89967D01*
X89567Y-140670D02*
Y-139870D01*
X86854Y-139629D02*
X87654D01*
X87254Y-140029D02*
Y-139229D01*
X118694Y-130047D02*
X119494D01*
X119095Y-130447D02*
Y-129647D01*
X116726Y-132047D02*
X117526D01*
X117126Y-132447D02*
Y-131647D01*
X106947Y-110236D02*
X107747D01*
X107346Y-110636D02*
Y-109836D01*
X104946Y-112205D02*
X105746D01*
X105347Y-112605D02*
Y-111805D01*
X98946Y-110236D02*
X99747D01*
X99347Y-110636D02*
Y-109836D01*
X109010Y-112236D02*
X109810D01*
X109409Y-112636D02*
Y-111836D01*
X118694Y-122047D02*
X119494D01*
X119095Y-122447D02*
Y-121647D01*
X-24022Y-229331D02*
X-23222D01*
X-23622Y-229731D02*
Y-228931D01*
X-24022Y-233268D02*
X-23222D01*
X-23622Y-233668D02*
Y-232868D01*
X-24022Y-237205D02*
X-23222D01*
X-23622Y-237605D02*
Y-236805D01*
X-24022Y-241142D02*
X-23222D01*
X-23622Y-241542D02*
Y-240742D01*
X-24022Y-282480D02*
X-23222D01*
X-23622Y-282880D02*
Y-282080D01*
X-24022Y-286417D02*
X-23222D01*
X-23622Y-286817D02*
Y-286017D01*
X-24022Y-290354D02*
X-23222D01*
X-23622Y-290754D02*
Y-289954D01*
X-24022Y-294291D02*
X-23222D01*
X-23622Y-294691D02*
Y-293891D01*
X-24022Y-335630D02*
X-23222D01*
X-23622Y-336030D02*
Y-335230D01*
X-24022Y-339567D02*
X-23222D01*
X-23622Y-339967D02*
Y-339167D01*
X-24022Y-346457D02*
X-23222D01*
X-23622Y-346857D02*
Y-346057D01*
X107009Y-141732D02*
X107809D01*
X107409Y-142132D02*
Y-141332D01*
X99010Y-141732D02*
X99809D01*
X99410Y-142132D02*
Y-141332D01*
X-24022Y-70866D02*
X-23222D01*
X-23622Y-71266D02*
Y-70466D01*
X-24022Y-66929D02*
X-23222D01*
X-23622Y-67329D02*
Y-66529D01*
X-24022Y-62992D02*
X-23222D01*
X-23622Y-63392D02*
Y-62592D01*
X-24022Y-60039D02*
X-23222D01*
X-23622Y-60439D02*
Y-59639D01*
X-24022Y-102362D02*
X-23222D01*
X-23622Y-102762D02*
Y-101962D01*
X-24022Y-106299D02*
X-23222D01*
X-23622Y-106699D02*
Y-105899D01*
X-24022Y-110236D02*
X-23222D01*
X-23622Y-110636D02*
Y-109836D01*
X-24022Y-114173D02*
X-23222D01*
X-23622Y-114573D02*
Y-113773D01*
X-24022Y-187992D02*
X-23222D01*
X-23622Y-188392D02*
Y-187592D01*
X-24022Y-184055D02*
X-23222D01*
X-23622Y-184455D02*
Y-183655D01*
X-24022Y-181102D02*
X-23222D01*
X-23622Y-181502D02*
Y-180702D01*
X-24022Y-177165D02*
X-23222D01*
X-23622Y-177565D02*
Y-176765D01*
X116726Y-128047D02*
X117526D01*
X117126Y-128447D02*
Y-127647D01*
X116726Y-124047D02*
X117526D01*
X117126Y-124447D02*
Y-123647D01*
X116726Y-119921D02*
X117526D01*
X117126Y-120321D02*
Y-119521D01*
X100883Y-112205D02*
X101683D01*
X101284Y-112605D02*
Y-111805D01*
X96883Y-112205D02*
X97684D01*
X97284Y-112605D02*
Y-111805D01*
X645445Y-95108D02*
X657645D01*
X651545Y-101208D02*
Y-89008D01*
X407256Y7254D02*
X419456D01*
X413356Y1154D02*
Y13354D01*
X407256Y-95108D02*
X419456D01*
X413356Y-101208D02*
Y-89008D01*
X645445Y7254D02*
X657645D01*
X651545Y1154D02*
Y13354D01*
X65780Y7412D02*
X77980D01*
X71880Y1312D02*
Y13512D01*
X303969Y-94950D02*
X316169D01*
X310069Y-101050D02*
Y-88850D01*
X303969Y7412D02*
X316169D01*
X310069Y1312D02*
Y13512D01*
X65780Y-94950D02*
X77980D01*
X71880Y-101050D02*
Y-88850D01*
X98622Y-121653D02*
X99410D01*
X99016Y-122047D02*
Y-121260D01*
X102953Y-121653D02*
X103740D01*
X103347Y-122047D02*
Y-121260D01*
X107283Y-121653D02*
X108071D01*
X107677Y-122047D02*
Y-121260D01*
X98622Y-125984D02*
X99410D01*
X99016Y-126378D02*
Y-125591D01*
X102953Y-125984D02*
X103740D01*
X103347Y-126378D02*
Y-125591D01*
X107283Y-125984D02*
X108071D01*
X107677Y-126378D02*
Y-125591D01*
X98622Y-130315D02*
X99410D01*
X99016Y-130709D02*
Y-129921D01*
X102953Y-130315D02*
X103740D01*
X103347Y-130709D02*
Y-129921D01*
X107283Y-130315D02*
X108071D01*
X107677Y-130709D02*
Y-129921D01*
X543891Y-195718D02*
X544691D01*
X544291Y-196118D02*
Y-195318D01*
X469121Y-137615D02*
X469921D01*
X469521Y-138015D02*
Y-137215D01*
X533478Y-117716D02*
X534278D01*
X533878Y-118116D02*
Y-117316D01*
X524206Y-125836D02*
X525006D01*
X524606Y-126236D02*
Y-125436D01*
X524157Y-128740D02*
X524957D01*
X524557Y-129140D02*
Y-128340D01*
X651157Y-64306D02*
X651957D01*
X651557Y-64706D02*
Y-63906D01*
X450450Y-174127D02*
X451250D01*
X450850Y-174527D02*
Y-173727D01*
X512395Y-104214D02*
X513195D01*
X512795Y-104614D02*
Y-103814D01*
X320466Y-272490D02*
X321266D01*
X320866Y-272890D02*
Y-272090D01*
X463151Y-116025D02*
X463951D01*
X463551Y-116425D02*
Y-115625D01*
X658065Y-37647D02*
X658865D01*
X658465Y-38047D02*
Y-37247D01*
X658065Y-29773D02*
X658865D01*
X658465Y-30173D02*
Y-29373D01*
X624600Y-21899D02*
X625400D01*
X625000Y-22299D02*
Y-21499D01*
X189954Y-377411D02*
X190754D01*
X190354Y-377811D02*
Y-377011D01*
X411939Y-123805D02*
X412739D01*
X412339Y-124206D02*
Y-123406D01*
X423813Y-175246D02*
X424613D01*
X424213Y-175646D02*
Y-174846D01*
X314561Y-118947D02*
X315361D01*
X314961Y-119346D02*
Y-118546D01*
X430407Y-175344D02*
X431207D01*
X430807Y-175744D02*
Y-174944D01*
X308616Y-128659D02*
X309416D01*
X309016Y-129059D02*
Y-128259D01*
X418498Y-144143D02*
X419298D01*
X418898Y-144543D02*
Y-143743D01*
X405112Y-136611D02*
X405912D01*
X405512Y-137011D02*
Y-136211D01*
X415705Y-144180D02*
X416505D01*
X416106Y-144580D02*
Y-143780D01*
X398168Y-145083D02*
X398968D01*
X398568Y-145483D02*
Y-144683D01*
X210033Y-374655D02*
X210833D01*
X210433Y-375055D02*
Y-374255D01*
X206096Y-374655D02*
X206896D01*
X206496Y-375055D02*
Y-374255D01*
X441726Y-306742D02*
X442526D01*
X442126Y-307142D02*
Y-306342D01*
X438970Y-306742D02*
X439770D01*
X439370Y-307142D02*
Y-306342D01*
X237592Y-374655D02*
X238392D01*
X237992Y-375055D02*
Y-374255D01*
X241529Y-374655D02*
X242329D01*
X241929Y-375055D02*
Y-374255D01*
X253255Y-374421D02*
X254055D01*
X253655Y-374821D02*
Y-374021D01*
X256490Y-374655D02*
X257290D01*
X256890Y-375055D02*
Y-374255D01*
X273025Y-374655D02*
X273825D01*
X273425Y-375055D02*
Y-374255D01*
X269102Y-374291D02*
X269902D01*
X269502Y-374691D02*
Y-373891D01*
X245939Y-386975D02*
X246739D01*
X246339Y-387375D02*
Y-386575D01*
X249009Y-387253D02*
X249810D01*
X249410Y-387653D02*
Y-386854D01*
X232080Y-387253D02*
X232880D01*
X232480Y-387653D02*
Y-386854D01*
X228931Y-387253D02*
X229731D01*
X229331Y-387653D02*
Y-386854D01*
X435820Y-306742D02*
X436621D01*
X436221Y-307142D02*
Y-306342D01*
X212395Y-387253D02*
X213195D01*
X212795Y-387653D02*
Y-386854D01*
X433065Y-306742D02*
X433865D01*
X433465Y-307142D02*
Y-306342D01*
X215545Y-387253D02*
X216345D01*
X215945Y-387653D02*
Y-386854D01*
X261606Y-387255D02*
X262406D01*
X262006Y-387655D02*
Y-386855D01*
X447632Y-306742D02*
X448431D01*
X448032Y-307142D02*
Y-306342D01*
X264757Y-387253D02*
X265558D01*
X265158Y-387653D02*
Y-386854D01*
X444876Y-306742D02*
X445676D01*
X445276Y-307142D02*
Y-306342D01*
X104128Y-92175D02*
X104928D01*
X104528Y-92575D02*
Y-91775D01*
X269285Y-106151D02*
X270085D01*
X269685Y-106551D02*
Y-105751D01*
X243694Y-109104D02*
X244495D01*
X244094Y-109504D02*
Y-108704D01*
X474895Y-133612D02*
X475695D01*
X475295Y-134012D02*
Y-133212D01*
X505506Y-131742D02*
X506306D01*
X505905Y-132142D02*
Y-131342D01*
X131490Y-72687D02*
X132290D01*
X131890Y-73087D02*
Y-72287D01*
X178734Y-386466D02*
X179534D01*
X179134Y-386866D02*
Y-386066D01*
X178734Y-389616D02*
X179534D01*
X179134Y-390016D02*
Y-389216D01*
X178143Y-377411D02*
X178943D01*
X178543Y-377811D02*
Y-377011D01*
X534000Y-126969D02*
X534800D01*
X534400Y-127368D02*
Y-126568D01*
X443498Y-175049D02*
X444298D01*
X443898Y-175449D02*
Y-174649D01*
X99010Y-65797D02*
X99809D01*
X99410Y-66197D02*
Y-65397D01*
X99010Y-57923D02*
X99809D01*
X99410Y-58323D02*
Y-57523D01*
X65545Y-65797D02*
X66345D01*
X65945Y-66197D02*
Y-65397D01*
X65545Y-50049D02*
X66345D01*
X65945Y-50449D02*
Y-49649D01*
X78340Y-238041D02*
X79140D01*
X78740Y-238441D02*
Y-237641D01*
X33065Y19833D02*
X33865D01*
X33465Y19433D02*
Y20233D01*
X39954Y19685D02*
X40754D01*
X40354Y19285D02*
Y20085D01*
X46844Y19685D02*
X47644D01*
X47244Y19285D02*
Y20085D01*
X482868Y-114025D02*
X483668D01*
X483268Y-114425D02*
Y-113625D01*
X491920Y-114970D02*
X492720D01*
X492319Y-115370D02*
Y-114570D01*
X486805Y-114057D02*
X487605D01*
X487205Y-114457D02*
Y-113657D01*
X456342Y-116043D02*
X457142D01*
X456742Y-116443D02*
Y-115643D01*
X463928Y-146397D02*
X464728D01*
X464328Y-146797D02*
Y-145997D01*
X468891Y-143848D02*
X469691D01*
X469291Y-144248D02*
Y-143448D01*
X460919Y-143750D02*
X461719D01*
X461319Y-144150D02*
Y-143350D01*
X266923Y-122883D02*
X267723D01*
X267323Y-123284D02*
Y-122484D01*
X456883Y-175147D02*
X457684D01*
X457283Y-175547D02*
Y-174747D01*
X468990Y-175147D02*
X469790D01*
X469390Y-175547D02*
Y-174747D01*
X543891Y-215403D02*
X544691D01*
X544291Y-215803D02*
Y-215003D01*
X512002Y-261958D02*
X512802D01*
X512402Y-262358D02*
Y-261558D01*
X512002Y-265108D02*
X512802D01*
X512402Y-265508D02*
Y-264708D01*
X512143Y-268065D02*
X512943D01*
X512543Y-268465D02*
Y-267665D01*
X437297Y-175246D02*
X438097D01*
X437697Y-175646D02*
Y-174846D01*
X433458Y-175246D02*
X434258D01*
X433858Y-175646D02*
Y-174846D01*
X404423Y-175344D02*
X405223D01*
X404823Y-175744D02*
Y-174944D01*
X401864Y-175344D02*
X402664D01*
X402264Y-175744D02*
Y-174944D01*
X236608Y-129576D02*
X237408D01*
X237008Y-129976D02*
Y-129176D01*
X308616Y-113986D02*
X309416D01*
X309016Y-114386D02*
Y-113586D01*
X193498Y-115009D02*
X194298D01*
X193898Y-115409D02*
Y-114609D01*
X193498Y-119931D02*
X194298D01*
X193898Y-120331D02*
Y-119531D01*
X308655Y-123868D02*
X309455D01*
X309055Y-124268D02*
Y-123468D01*
X575332Y-124606D02*
X576932D01*
X576132Y-125406D02*
Y-123806D01*
X182277Y-386466D02*
X183077D01*
X182677Y-386866D02*
Y-386066D01*
X186214Y-386466D02*
X187014D01*
X186614Y-386866D02*
Y-386066D01*
X182277Y-389616D02*
X183077D01*
X182677Y-390016D02*
Y-389216D01*
X186214Y-389616D02*
X187014D01*
X186614Y-390016D02*
Y-389216D01*
M02*
